(kicad_pcb
	(version 20260206)
	(generator "pcbnew")
	(generator_version "10.0")
	(general
		(thickness 1.6)
		(legacy_teardrops no)
	)
	(paper "A4")
	(title_block
		(title "timecard-production-celestica-r4006 — R4006-B0001-02_R01.brd")
		(comment 1 "Time Appliance Project (Time Card) / footprints 1024-1028 of 1113")
	)
	(layers
		(0 "F.Cu" signal "TOP")
		(4 "In1.Cu" signal "L02_GND1")
		(6 "In2.Cu" signal "L03_SIG1")
		(8 "In3.Cu" signal "L04_GND2")
		(10 "In4.Cu" signal "L05_VCC1")
		(12 "In5.Cu" signal "L06_VCC2")
		(14 "In6.Cu" signal "L07_GND3")
		(16 "In7.Cu" signal "L08_SIG2")
		(18 "In8.Cu" signal "L09_GND4")
		(2 "B.Cu" signal "BOTTOM")
		(9 "F.Adhes" user "F.Adhesive")
		(11 "B.Adhes" user "B.Adhesive")
		(13 "F.Paste" user "Package Geometry/Pastemask Top")
		(15 "B.Paste" user "Package Geometry/Pastemask Bottom")
		(5 "F.SilkS" user "Ref Des/Silkscreen Top")
		(7 "B.SilkS" user "Ref Des/Silkscreen Bottom")
		(1 "F.Mask" user "Board Geometry/Soldermask Top")
		(3 "B.Mask" user "Board Geometry/Soldermask Bottom")
		(17 "Dwgs.User" user "User.Drawings")
		(19 "Cmts.User" user "User.Comments")
		(21 "Eco1.User" user "User.Eco1")
		(23 "Eco2.User" user "User.Eco2")
		(25 "Edge.Cuts" user "Board Geometry/Outline")
		(27 "Margin" user)
		(31 "F.CrtYd" user "Package Geometry/Place Bound Top")
		(29 "B.CrtYd" user "Package Geometry/Place Bound Bottom")
		(35 "F.Fab" user "Ref Des/Assembly Top")
		(33 "B.Fab" user "Ref Des/Assembly Bottom")
	)
	(footprint ""
		(layer "B.Cu")
		(at 112.84712 -46.322996 -90)
		(property "Reference" "R436"
			(at 2.032 43.029886 270)
			(unlocked yes)
			(layer "B.SilkS")
			(effects
				(font
					(size 0.635 0.4064)
					(thickness 0.1524)
				)
				(justify mirror)
			)
		)
		(property "Value" "VAL*"
			(at 0 3.718306 270)
			(unlocked yes)
			(layer "B.Fab")
			(hide yes)
			(effects
				(font
					(size 0.7874 0.5842)
					(thickness 0.127)
				)
				(justify mirror)
			)
		)
		(property "Tolerance" "TOL*"
			(at 0 4.861306 270)
			(unlocked yes)
			(layer "Cmts.User")
			(hide yes)
			(effects
				(font
					(size 0.7874 0.5842)
					(thickness 0.127)
				)
				(justify mirror)
			)
		)
		(property "User Part Number" "PARTNUM*"
			(at 0 2.575306 270)
			(unlocked yes)
			(layer "Cmts.User")
			(hide yes)
			(effects
				(font
					(size 0.7874 0.5842)
					(thickness 0.127)
				)
				(justify mirror)
			)
		)
		(property "Device Type" "RESISTOR-G155-11502-01,15KOHM,A"
			(at 0 1.432306 270)
			(unlocked yes)
			(layer "B.Fab")
			(hide yes)
			(effects
				(font
					(size 0.7874 0.5842)
					(thickness 0.127)
				)
				(justify mirror)
			)
		)
		(duplicate_pad_numbers_are_jumpers no)
		(fp_line
			(start -0.970026 0.4699)
			(end 0.970026 0.4699)
			(stroke
				(width 0.1)
				(type default)
			)
			(layer "B.SilkS")
		)
		(fp_line
			(start 0.970026 0.4699)
			(end 0.970026 -0.4699)
			(stroke
				(width 0.1)
				(type default)
			)
			(layer "B.SilkS")
		)
		(fp_line
			(start -0.970026 -0.4699)
			(end -0.970026 0.4699)
			(stroke
				(width 0.1)
				(type default)
			)
			(layer "B.SilkS")
		)
		(fp_line
			(start 0.970026 -0.4699)
			(end -0.970026 -0.4699)
			(stroke
				(width 0.1)
				(type default)
			)
			(layer "B.SilkS")
		)
		(fp_poly
			(pts
				(xy 0.970026 0.4699) (xy -0.970026 0.4699) (xy -0.970026 -0.4699) (xy 0.970026 -0.4699)
			)
			(stroke
				(width 0)
				(type default)
			)
			(fill no)
			(layer "B.CrtYd")
		)
		(fp_line
			(start -0.508 0.3048)
			(end 0.508 0.3048)
			(stroke
				(width 0.1)
				(type default)
			)
			(layer "B.Fab")
		)
		(fp_line
			(start 0.508 0.3048)
			(end 0.508 -0.3048)
			(stroke
				(width 0.1)
				(type default)
			)
			(layer "B.Fab")
		)
		(fp_line
			(start -0.508 -0.3048)
			(end -0.508 0.3048)
			(stroke
				(width 0.1)
				(type default)
			)
			(layer "B.Fab")
		)
		(fp_line
			(start 0.508 -0.3048)
			(end -0.508 -0.3048)
			(stroke
				(width 0.1)
				(type default)
			)
			(layer "B.Fab")
		)
		(pad "1" smd circle
			(at 0.500126 0 90)
			(size 0.635 0.635)
			(layers "B.Cu" "B.Mask" "B.Paste")
			(net "SG")
		)
		(pad "2" smd circle
			(at -0.500126 0 90)
			(size 0.635 0.635)
			(layers "B.Cu" "B.Mask" "B.Paste")
			(net "MAC_USB_DP")
		)
	)
	(footprint ""
		(layer "B.Cu")
		(at 34.544 -83.312 180)
		(property "Reference" "R132"
			(at 0.381 2.37363 0)
			(unlocked yes)
			(layer "B.SilkS")
			(effects
				(font
					(size 0.7874 0.5842)
					(thickness 0.1524)
				)
				(justify mirror)
			)
		)
		(property "Value" "VAL*"
			(at -0.02032 2.13233 180)
			(unlocked yes)
			(layer "B.Fab")
			(hide yes)
			(effects
				(font
					(size 0.7874 0.5842)
					(thickness 0.1524)
				)
				(justify mirror)
			)
		)
		(property "Tolerance" "TOL*"
			(at -0.044704 3.05435 180)
			(unlocked yes)
			(layer "Cmts.User")
			(hide yes)
			(effects
				(font
					(size 0.7874 0.5842)
					(thickness 0.1524)
				)
				(justify mirror)
			)
		)
		(property "User Part Number" "PARTNUM*"
			(at -0.02032 4.024884 180)
			(unlocked yes)
			(layer "Cmts.User")
			(hide yes)
			(effects
				(font
					(size 0.7874 0.5842)
					(thickness 0.1524)
				)
				(justify mirror)
			)
		)
		(property "Device Type" "RESISTOR-G155-11000-01,100OHM,A"
			(at -0.008382 1.210564 180)
			(unlocked yes)
			(layer "B.Fab")
			(hide yes)
			(effects
				(font
					(size 0.7874 0.5842)
					(thickness 0.1524)
				)
				(justify mirror)
			)
		)
		(duplicate_pad_numbers_are_jumpers no)
		(fp_line
			(start 1.143 0.5588)
			(end -1.143 0.5588)
			(stroke
				(width 0.1)
				(type default)
			)
			(layer "B.SilkS")
		)
		(fp_line
			(start 1.143 -0.5588)
			(end 1.143 0.5588)
			(stroke
				(width 0.1)
				(type default)
			)
			(layer "B.SilkS")
		)
		(fp_line
			(start -1.143 0.5588)
			(end -1.143 -0.5588)
			(stroke
				(width 0.1)
				(type default)
			)
			(layer "B.SilkS")
		)
		(fp_line
			(start -1.143 -0.5588)
			(end 1.143 -0.5588)
			(stroke
				(width 0.1)
				(type default)
			)
			(layer "B.SilkS")
		)
		(fp_rect
			(start 1.143 -0.5588)
			(end -1.143 0.5588)
			(stroke
				(width 0)
				(type default)
			)
			(fill no)
			(layer "B.CrtYd")
		)
		(fp_line
			(start 0.508 0.3048)
			(end -0.508 0.3048)
			(stroke
				(width 0.1)
				(type default)
			)
			(layer "B.Fab")
		)
		(fp_line
			(start 0.508 -0.3048)
			(end 0.508 0.3048)
			(stroke
				(width 0.1)
				(type default)
			)
			(layer "B.Fab")
		)
		(fp_line
			(start -0.508 0.3048)
			(end -0.508 -0.3048)
			(stroke
				(width 0.1)
				(type default)
			)
			(layer "B.Fab")
		)
		(fp_line
			(start -0.508 -0.3048)
			(end 0.508 -0.3048)
			(stroke
				(width 0.1)
				(type default)
			)
			(layer "B.Fab")
		)
		(pad "1" smd rect
			(at 0.5334 0)
			(size 0.7112 0.6096)
			(layers "B.Cu" "B.Mask" "B.Paste")
			(net "R_FT4232_CHD_RX")
		)
		(pad "2" smd rect
			(at -0.5334 0)
			(size 0.7112 0.6096)
			(layers "B.Cu" "B.Mask" "B.Paste")
			(net "FT4232_CHD_RX")
		)
		(zone
			(layer "B.Cu")
			(hatch none 0.5)
			(connect_pads
				(clearance 0)
			)
			(min_thickness 0.25)
			(keepout
				(tracks allowed)
				(vias not_allowed)
				(pads allowed)
				(copperpour not_allowed)
				(footprints allowed)
			)
			(placement
				(enabled no)
				(sheetname "")
			)
			(fill
				(thermal_gap 0.5)
				(thermal_bridge_width 0.5)
				(island_removal_mode 0)
			)
			(polygon
				(pts
					(xy 34.4678 -83.0072) (xy 34.6202 -83.0072) (xy 34.6202 -83.6168) (xy 34.4678 -83.6168)
				)
			)
		)
	)
	(footprint ""
		(layer "B.Cu")
		(at 117.346984 -42.82313)
		(property "Reference" "C210"
			(at 4.033266 0.78613 270)
			(unlocked yes)
			(layer "B.SilkS")
			(effects
				(font
					(size 0.635 0.4064)
					(thickness 0.1524)
				)
				(justify mirror)
			)
		)
		(property "Value" "VAL*"
			(at 0 3.718306 0)
			(unlocked yes)
			(layer "B.Fab")
			(hide yes)
			(effects
				(font
					(size 0.7874 0.5842)
					(thickness 0.127)
				)
				(justify mirror)
			)
		)
		(property "Tolerance" "TOL*"
			(at 0 4.861306 0)
			(unlocked yes)
			(layer "Cmts.User")
			(hide yes)
			(effects
				(font
					(size 0.7874 0.5842)
					(thickness 0.127)
				)
				(justify mirror)
			)
		)
		(property "User Part Number" "PARTNUM*"
			(at 0 2.575306 0)
			(unlocked yes)
			(layer "Cmts.User")
			(hide yes)
			(effects
				(font
					(size 0.7874 0.5842)
					(thickness 0.127)
				)
				(justify mirror)
			)
		)
		(property "Device Type" "CAPACITOR-G105-0B104-CK,0.1UF,A"
			(at 0 1.432306 0)
			(unlocked yes)
			(layer "B.Fab")
			(hide yes)
			(effects
				(font
					(size 0.7874 0.5842)
					(thickness 0.127)
				)
				(justify mirror)
			)
		)
		(duplicate_pad_numbers_are_jumpers no)
		(fp_line
			(start -0.970026 -0.4699)
			(end -0.970026 0.4699)
			(stroke
				(width 0.1)
				(type default)
			)
			(layer "B.SilkS")
		)
		(fp_line
			(start -0.970026 0.4699)
			(end 0.970026 0.4699)
			(stroke
				(width 0.1)
				(type default)
			)
			(layer "B.SilkS")
		)
		(fp_line
			(start 0.970026 -0.4699)
			(end -0.970026 -0.4699)
			(stroke
				(width 0.1)
				(type default)
			)
			(layer "B.SilkS")
		)
		(fp_line
			(start 0.970026 0.4699)
			(end 0.970026 -0.4699)
			(stroke
				(width 0.1)
				(type default)
			)
			(layer "B.SilkS")
		)
		(fp_poly
			(pts
				(xy 0.970026 0.4699) (xy -0.970026 0.4699) (xy -0.970026 -0.4699) (xy 0.970026 -0.4699)
			)
			(stroke
				(width 0)
				(type default)
			)
			(fill no)
			(layer "B.CrtYd")
		)
		(fp_line
			(start -0.508 -0.3048)
			(end -0.508 0.3048)
			(stroke
				(width 0.1)
				(type default)
			)
			(layer "B.Fab")
		)
		(fp_line
			(start -0.508 0.3048)
			(end 0.508 0.3048)
			(stroke
				(width 0.1)
				(type default)
			)
			(layer "B.Fab")
		)
		(fp_line
			(start 0.508 -0.3048)
			(end -0.508 -0.3048)
			(stroke
				(width 0.1)
				(type default)
			)
			(layer "B.Fab")
		)
		(fp_line
			(start 0.508 0.3048)
			(end 0.508 -0.3048)
			(stroke
				(width 0.1)
				(type default)
			)
			(layer "B.Fab")
		)
		(pad "1" smd circle
			(at 0.500126 0 180)
			(size 0.635 0.635)
			(layers "B.Cu" "B.Mask" "B.Paste")
			(net "XP3R3V_FPGA")
		)
		(pad "2" smd circle
			(at -0.500126 0 180)
			(size 0.635 0.635)
			(layers "B.Cu" "B.Mask" "B.Paste")
			(net "SG")
		)
	)
	(footprint ""
		(layer "B.Cu")
		(at 124.587 -45.974)
		(property "Reference" "R195"
			(at 3.683 0.16637 0)
			(unlocked yes)
			(layer "B.SilkS")
			(effects
				(font
					(size 0.7874 0.5842)
					(thickness 0.1524)
				)
				(justify mirror)
			)
		)
		(property "Value" "VAL*"
			(at -0.02032 2.13233 0)
			(unlocked yes)
			(layer "B.Fab")
			(hide yes)
			(effects
				(font
					(size 0.7874 0.5842)
					(thickness 0.1524)
				)
				(justify mirror)
			)
		)
		(property "Tolerance" "TOL*"
			(at -0.044704 3.05435 0)
			(unlocked yes)
			(layer "Cmts.User")
			(hide yes)
			(effects
				(font
					(size 0.7874 0.5842)
					(thickness 0.1524)
				)
				(justify mirror)
			)
		)
		(property "User Part Number" "PARTNUM*"
			(at -0.02032 4.024884 0)
			(unlocked yes)
			(layer "Cmts.User")
			(hide yes)
			(effects
				(font
					(size 0.7874 0.5842)
					(thickness 0.1524)
				)
				(justify mirror)
			)
		)
		(property "Device Type" "RESISTOR-G155-133R0-01,33OHM,1%"
			(at -0.008382 1.210564 0)
			(unlocked yes)
			(layer "B.Fab")
			(hide yes)
			(effects
				(font
					(size 0.7874 0.5842)
					(thickness 0.1524)
				)
				(justify mirror)
			)
		)
		(duplicate_pad_numbers_are_jumpers no)
		(fp_line
			(start -1.143 -0.5588)
			(end 1.143 -0.5588)
			(stroke
				(width 0.1)
				(type default)
			)
			(layer "B.SilkS")
		)
		(fp_line
			(start -1.143 0.5588)
			(end -1.143 -0.5588)
			(stroke
				(width 0.1)
				(type default)
			)
			(layer "B.SilkS")
		)
		(fp_line
			(start 1.143 -0.5588)
			(end 1.143 0.5588)
			(stroke
				(width 0.1)
				(type default)
			)
			(layer "B.SilkS")
		)
		(fp_line
			(start 1.143 0.5588)
			(end -1.143 0.5588)
			(stroke
				(width 0.1)
				(type default)
			)
			(layer "B.SilkS")
		)
		(fp_rect
			(start -1.143 -0.5588)
			(end 1.143 0.5588)
			(stroke
				(width 0)
				(type default)
			)
			(fill no)
			(layer "B.CrtYd")
		)
		(fp_line
			(start -0.508 -0.3048)
			(end 0.508 -0.3048)
			(stroke
				(width 0.1)
				(type default)
			)
			(layer "B.Fab")
		)
		(fp_line
			(start -0.508 0.3048)
			(end -0.508 -0.3048)
			(stroke
				(width 0.1)
				(type default)
			)
			(layer "B.Fab")
		)
		(fp_line
			(start 0.508 -0.3048)
			(end 0.508 0.3048)
			(stroke
				(width 0.1)
				(type default)
			)
			(layer "B.Fab")
		)
		(fp_line
			(start 0.508 0.3048)
			(end -0.508 0.3048)
			(stroke
				(width 0.1)
				(type default)
			)
			(layer "B.Fab")
		)
		(pad "1" smd rect
			(at 0.5334 0 180)
			(size 0.7112 0.6096)
			(layers "B.Cu" "B.Mask" "B.Paste")
			(net "FPGA_TDO")
		)
		(pad "2" smd rect
			(at -0.5334 0 180)
			(size 0.7112 0.6096)
			(layers "B.Cu" "B.Mask" "B.Paste")
			(net "R_FPGA_TDO")
		)
		(zone
			(layer "B.Cu")
			(hatch none 0.5)
			(connect_pads
				(clearance 0)
			)
			(min_thickness 0.25)
			(keepout
				(tracks allowed)
				(vias not_allowed)
				(pads allowed)
				(copperpour not_allowed)
				(footprints allowed)
			)
			(placement
				(enabled no)
				(sheetname "")
			)
			(fill
				(thermal_gap 0.5)
				(thermal_bridge_width 0.5)
				(island_removal_mode 0)
			)
			(polygon
				(pts
					(xy 124.5108 -46.2788) (xy 124.5108 -45.6692) (xy 124.6632 -45.6692) (xy 124.6632 -46.2788)
				)
			)
		)
	)
	(footprint ""
		(layer "B.Cu")
		(at 47.879 -75.184 -90)
		(property "Reference" "R488"
			(at 0.381 -1.23063 270)
			(unlocked yes)
			(layer "B.SilkS")
			(effects
				(font
					(size 0.7874 0.5842)
					(thickness 0.1524)
				)
				(justify mirror)
			)
		)
		(property "Value" "VAL*"
			(at -0.02032 2.13233 270)
			(unlocked yes)
			(layer "B.Fab")
			(hide yes)
			(effects
				(font
					(size 0.7874 0.5842)
					(thickness 0.1524)
				)
				(justify mirror)
			)
		)
		(property "Tolerance" "TOL*"
			(at -0.044704 3.05435 270)
			(unlocked yes)
			(layer "Cmts.User")
			(hide yes)
			(effects
				(font
					(size 0.7874 0.5842)
					(thickness 0.1524)
				)
				(justify mirror)
			)
		)
		(property "User Part Number" "PARTNUM*"
			(at -0.02032 4.024884 270)
			(unlocked yes)
			(layer "Cmts.User")
			(hide yes)
			(effects
				(font
					(size 0.7874 0.5842)
					(thickness 0.1524)
				)
				(justify mirror)
			)
		)
		(property "Device Type" "RESISTOR-G155-11002-01,10KOHM,A"
			(at -0.008382 1.210564 270)
			(unlocked yes)
			(layer "B.Fab")
			(hide yes)
			(effects
				(font
					(size 0.7874 0.5842)
					(thickness 0.1524)
				)
				(justify mirror)
			)
		)
		(duplicate_pad_numbers_are_jumpers no)
		(fp_line
			(start -1.143 0.5588)
			(end -1.143 -0.5588)
			(stroke
				(width 0.1)
				(type default)
			)
			(layer "B.SilkS")
		)
		(fp_line
			(start 1.143 0.5588)
			(end -1.143 0.5588)
			(stroke
				(width 0.1)
				(type default)
			)
			(layer "B.SilkS")
		)
		(fp_line
			(start -1.143 -0.5588)
			(end 1.143 -0.5588)
			(stroke
				(width 0.1)
				(type default)
			)
			(layer "B.SilkS")
		)
		(fp_line
			(start 1.143 -0.5588)
			(end 1.143 0.5588)
			(stroke
				(width 0.1)
				(type default)
			)
			(layer "B.SilkS")
		)
		(fp_poly
			(pts
				(xy 1.143 0.5588) (xy -1.143 0.5588) (xy -1.143 -0.5588) (xy 1.143 -0.5588)
			)
			(stroke
				(width 0)
				(type default)
			)
			(fill no)
			(layer "B.CrtYd")
		)
		(fp_line
			(start -0.508 0.3048)
			(end -0.508 -0.3048)
			(stroke
				(width 0.1)
				(type default)
			)
			(layer "B.Fab")
		)
		(fp_line
			(start 0.508 0.3048)
			(end -0.508 0.3048)
			(stroke
				(width 0.1)
				(type default)
			)
			(layer "B.Fab")
		)
		(fp_line
			(start -0.508 -0.3048)
			(end 0.508 -0.3048)
			(stroke
				(width 0.1)
				(type default)
			)
			(layer "B.Fab")
		)
		(fp_line
			(start 0.508 -0.3048)
			(end 0.508 0.3048)
			(stroke
				(width 0.1)
				(type default)
			)
			(layer "B.Fab")
		)
		(pad "1" smd rect
			(at 0.5334 0 90)
			(size 0.7112 0.6096)
			(layers "B.Cu" "B.Mask" "B.Paste")
			(net "UNNAMED_525_CAPACITOR_I14_1")
		)
		(pad "2" smd rect
			(at -0.5334 0 90)
			(size 0.7112 0.6096)
			(layers "B.Cu" "B.Mask" "B.Paste")
			(net "SG")
		)
		(zone
			(layer "B.Cu")
			(hatch none 0.5)
			(connect_pads
				(clearance 0)
			)
			(min_thickness 0.25)
			(keepout
				(tracks allowed)
				(vias not_allowed)
				(pads allowed)
				(copperpour not_allowed)
				(footprints allowed)
			)
			(placement
				(enabled no)
				(sheetname "")
			)
			(fill
				(thermal_gap 0.5)
				(thermal_bridge_width 0.5)
				(island_removal_mode 0)
			)
			(polygon
				(pts
					(xy 47.5742 -75.1078) (xy 48.1838 -75.1078) (xy 48.1838 -75.2602) (xy 47.5742 -75.2602)
				)
			)
		)
		(zone
			(layer "B.Cu")
			(hatch none 0.5)
			(connect_pads
				(clearance 0)
			)
			(min_thickness 0.25)
			(keepout
				(tracks not_allowed)
				(vias allowed)
				(pads allowed)
				(copperpour not_allowed)
				(footprints allowed)
			)
			(placement
				(enabled no)
				(sheetname "")
			)
			(fill
				(thermal_gap 0.5)
				(thermal_bridge_width 0.5)
				(island_removal_mode 0)
			)
			(polygon
				(pts
					(xy 47.5742 -75.1078) (xy 48.1838 -75.1078) (xy 48.1838 -75.2602) (xy 47.5742 -75.2602)
				)
			)
		)
	)
)
